# T6G (Grand Teton) — schematic netlist excerpt (pin names and nets, part order shuffled) for the footprints in the layout excerpt that follows; sources: Cadence DE-HDL packaged netlist, KiCad conversion of 04192023_DAF0TMB3IC0_F0TG_MB_C_brd_V02_OCP.brd

C263  Q_CAP  22UF 4V 20% X6S  pkg C0402  page 69 : A = PVDDCR_CPU0_P0 ; B = GND
C6034  Q_CAP  0.1UF 25V 10% X7R  pkg 0402  page 177 : A = P1V2_CPU0_USB_DVDD12 ; B = GND

(kicad_pcb
	(version 20260206)
	(generator "pcbnew")
	(generator_version "10.0")
	(general
		(thickness 1.6)
		(legacy_teardrops no)
	)
	(paper "A4")
	(title_block
		(title "04192023_DAF0TMB3IC0_F0TG_MB_C_brd_V02_OCP.brd")
		(comment 1 "Grand Teton / footprints 5136-5137 of 8354")
	)
	(layers
		(0 "F.Cu" signal "TOP")
		(4 "In1.Cu" signal "GND")
		(6 "In2.Cu" signal "IN1")
		(8 "In3.Cu" signal "GND1")
		(10 "In4.Cu" signal "IN2")
		(12 "In5.Cu" signal "GND2")
		(14 "In6.Cu" signal "IN3")
		(16 "In7.Cu" signal "GND3")
		(18 "In8.Cu" signal "VCC")
		(20 "In9.Cu" signal "VCC1")
		(22 "In10.Cu" signal "GND4")
		(24 "In11.Cu" signal "IN4")
		(26 "In12.Cu" signal "GND5")
		(28 "In13.Cu" signal "IN5")
		(30 "In14.Cu" signal "GND6")
		(32 "In15.Cu" signal "IN6")
		(34 "In16.Cu" signal "GND7")
		(2 "B.Cu" signal "BOTTOM")
		(9 "F.Adhes" user "F.Adhesive")
		(11 "B.Adhes" user "B.Adhesive")
		(13 "F.Paste" user "Package Geometry/Pastemask Top")
		(15 "B.Paste" user "Package Geometry/Pastemask Bottom")
		(5 "F.SilkS" user "Ref Des/Silkscreen Top")
		(7 "B.SilkS" user "Ref Des/Silkscreen Bottom")
		(1 "F.Mask" user "Board Geometry/Soldermask Top")
		(3 "B.Mask" user "Board Geometry/Soldermask Bottom")
		(17 "Dwgs.User" user "User.Drawings")
		(19 "Cmts.User" user "User.Comments")
		(21 "Eco1.User" user "User.Eco1")
		(23 "Eco2.User" user "User.Eco2")
		(25 "Edge.Cuts" user "Board Geometry/Outline")
		(27 "Margin" user)
		(31 "F.CrtYd" user "Package Geometry/Place Bound Top")
		(29 "B.CrtYd" user "Package Geometry/Place Bound Bottom")
		(35 "F.Fab" user "Ref Des/Assembly Top")
		(33 "B.Fab" user "Ref Des/Assembly Bottom")
	)
	(footprint ""
		(layer "B.Cu")
		(at 355.041454 -248.47931 180)
		(property "Reference" "C263"
			(at 0 0 0)
			(layer "B.SilkS")
			(hide yes)
			(effects
				(font
					(size 1.27 1.27)
				)
				(justify mirror)
			)
		)
		(property "Value" ""
			(at 0 0 0)
			(layer "B.Fab")
			(effects
				(font
					(size 1.27 1.27)
				)
				(justify mirror)
			)
		)
		(duplicate_pad_numbers_are_jumpers no)
		(fp_line
			(start 0.7874 0.4064)
			(end 0.7874 -0.4064)
			(stroke
				(width 0.1524)
				(type default)
			)
			(layer "B.SilkS")
		)
		(fp_line
			(start 0.7874 -0.4064)
			(end -0.7874 -0.4064)
			(stroke
				(width 0.1524)
				(type default)
			)
			(layer "B.SilkS")
		)
		(fp_line
			(start -0.7874 0.4064)
			(end 0.7874 0.4064)
			(stroke
				(width 0.1524)
				(type default)
			)
			(layer "B.SilkS")
		)
		(fp_line
			(start -0.7874 -0.4064)
			(end -0.7874 0.4064)
			(stroke
				(width 0.1524)
				(type default)
			)
			(layer "B.SilkS")
		)
		(fp_line
			(start 0.67945 0.3048)
			(end 0.67945 -0.305054)
			(stroke
				(width 0.1)
				(type default)
			)
			(layer "B.Fab")
		)
		(fp_line
			(start 0.67945 -0.305054)
			(end 0.12065 -0.305054)
			(stroke
				(width 0.1)
				(type default)
			)
			(layer "B.Fab")
		)
		(fp_line
			(start 0.12065 0.3048)
			(end 0.67945 0.3048)
			(stroke
				(width 0.1)
				(type default)
			)
			(layer "B.Fab")
		)
		(fp_line
			(start 0.12065 0.2794)
			(end 0.12065 0.3048)
			(stroke
				(width 0.1)
				(type default)
			)
			(layer "B.Fab")
		)
		(fp_line
			(start 0.12065 -0.2794)
			(end -0.12065 -0.2794)
			(stroke
				(width 0.1)
				(type default)
			)
			(layer "B.Fab")
		)
		(fp_line
			(start 0.12065 -0.305054)
			(end 0.12065 -0.2794)
			(stroke
				(width 0.1)
				(type default)
			)
			(layer "B.Fab")
		)
		(fp_line
			(start -0.120396 0.3048)
			(end -0.120396 0.2794)
			(stroke
				(width 0.1)
				(type default)
			)
			(layer "B.Fab")
		)
		(fp_line
			(start -0.120396 0.2794)
			(end 0.12065 0.2794)
			(stroke
				(width 0.1)
				(type default)
			)
			(layer "B.Fab")
		)
		(fp_line
			(start -0.12065 -0.2794)
			(end -0.12065 -0.3048)
			(stroke
				(width 0.1)
				(type default)
			)
			(layer "B.Fab")
		)
		(fp_line
			(start -0.12065 -0.3048)
			(end -0.67945 -0.3048)
			(stroke
				(width 0.1)
				(type default)
			)
			(layer "B.Fab")
		)
		(fp_line
			(start -0.67945 0.3048)
			(end -0.120396 0.3048)
			(stroke
				(width 0.1)
				(type default)
			)
			(layer "B.Fab")
		)
		(fp_line
			(start -0.67945 -0.3048)
			(end -0.67945 0.3048)
			(stroke
				(width 0.1)
				(type default)
			)
			(layer "B.Fab")
		)
		(pad "1" smd circle
			(at 0.40005 0)
			(size 0 0)
			(layers "B.Cu" "B.Mask" "B.Paste")
			(net "PVDDCR_CPU0_P0")
		)
		(pad "2" smd circle
			(at -0.40005 0)
			(size 0 0)
			(layers "B.Cu" "B.Mask" "B.Paste")
			(net "GND")
		)
	)
	(footprint ""
		(layer "B.Cu")
		(at 134.840218 -41.127426)
		(property "Reference" "C6034"
			(at 0 0 0)
			(layer "B.SilkS")
			(hide yes)
			(effects
				(font
					(size 1.27 1.27)
				)
				(justify mirror)
			)
		)
		(property "Value" ""
			(at 0 0 0)
			(layer "B.Fab")
			(effects
				(font
					(size 1.27 1.27)
				)
				(justify mirror)
			)
		)
		(duplicate_pad_numbers_are_jumpers no)
		(fp_line
			(start -0.7874 -0.4064)
			(end -0.7874 0.4064)
			(stroke
				(width 0.1524)
				(type default)
			)
			(layer "B.SilkS")
		)
		(fp_line
			(start -0.7874 0.4064)
			(end 0.7874 0.4064)
			(stroke
				(width 0.1524)
				(type default)
			)
			(layer "B.SilkS")
		)
		(fp_line
			(start 0.7874 -0.4064)
			(end -0.7874 -0.4064)
			(stroke
				(width 0.1524)
				(type default)
			)
			(layer "B.SilkS")
		)
		(fp_line
			(start 0.7874 0.4064)
			(end 0.7874 -0.4064)
			(stroke
				(width 0.1524)
				(type default)
			)
			(layer "B.SilkS")
		)
		(fp_line
			(start -0.67945 -0.3048)
			(end -0.67945 0.3048)
			(stroke
				(width 0.1)
				(type default)
			)
			(layer "B.Fab")
		)
		(fp_line
			(start -0.67945 0.3048)
			(end -0.120396 0.3048)
			(stroke
				(width 0.1)
				(type default)
			)
			(layer "B.Fab")
		)
		(fp_line
			(start -0.12065 -0.3048)
			(end -0.67945 -0.3048)
			(stroke
				(width 0.1)
				(type default)
			)
			(layer "B.Fab")
		)
		(fp_line
			(start -0.12065 -0.2794)
			(end -0.12065 -0.3048)
			(stroke
				(width 0.1)
				(type default)
			)
			(layer "B.Fab")
		)
		(fp_line
			(start -0.120396 0.2794)
			(end 0.12065 0.2794)
			(stroke
				(width 0.1)
				(type default)
			)
			(layer "B.Fab")
		)
		(fp_line
			(start -0.120396 0.3048)
			(end -0.120396 0.2794)
			(stroke
				(width 0.1)
				(type default)
			)
			(layer "B.Fab")
		)
		(fp_line
			(start 0.12065 -0.305054)
			(end 0.12065 -0.2794)
			(stroke
				(width 0.1)
				(type default)
			)
			(layer "B.Fab")
		)
		(fp_line
			(start 0.12065 -0.2794)
			(end -0.12065 -0.2794)
			(stroke
				(width 0.1)
				(type default)
			)
			(layer "B.Fab")
		)
		(fp_line
			(start 0.12065 0.2794)
			(end 0.12065 0.3048)
			(stroke
				(width 0.1)
				(type default)
			)
			(layer "B.Fab")
		)
		(fp_line
			(start 0.12065 0.3048)
			(end 0.67945 0.3048)
			(stroke
				(width 0.1)
				(type default)
			)
			(layer "B.Fab")
		)
		(fp_line
			(start 0.67945 -0.305054)
			(end 0.12065 -0.305054)
			(stroke
				(width 0.1)
				(type default)
			)
			(layer "B.Fab")
		)
		(fp_line
			(start 0.67945 0.3048)
			(end 0.67945 -0.305054)
			(stroke
				(width 0.1)
				(type default)
			)
			(layer "B.Fab")
		)
		(pad "1" smd circle
			(at 0.40005 0 180)
			(size 0 0)
			(layers "B.Cu" "B.Mask" "B.Paste")
			(net "P1V2_CPU0_USB_DVDD12")
		)
		(pad "2" smd circle
			(at -0.40005 0 180)
			(size 0 0)
			(layers "B.Cu" "B.Mask" "B.Paste")
			(net "GND")
		)
	)
)
